# BASEBOARD_FAB2 (Tioga Pass) — schematic netlist excerpt (pin names and nets, part order shuffled) for the footprints in the layout excerpt that follows; sources: Cadence DE-HDL packaged netlist, KiCad conversion of Wiwynn_Tioga_Pass_MB.brd

R3D19  RES  49.9 1% CHIP  pkg 0402  page 55 : A = A_CPU1_UPI01_RBIAS ; B = GND
R1C6  RES  1.00K 1% EMPTY  pkg 0402  page 210 : A = VSENSE_PVSA_CPU1_P ; B = VSENSE_PVSA_CPU1_N

(kicad_pcb
	(version 20260206)
	(generator "pcbnew")
	(generator_version "10.0")
	(general
		(thickness 1.6)
		(legacy_teardrops no)
	)
	(paper "A4")
	(title_block
		(title "Wiwynn_Tioga_Pass_MB.brd")
		(comment 1 "Tioga Pass / footprints 1564-1565 of 4770")
	)
	(layers
		(0 "F.Cu" signal "TOP")
		(4 "In1.Cu" signal "L2GND")
		(6 "In2.Cu" signal "L3")
		(8 "In3.Cu" signal "L4GND")
		(10 "In4.Cu" signal "L5")
		(12 "In5.Cu" signal "L6GND")
		(14 "In6.Cu" signal "L7VCC")
		(16 "In7.Cu" signal "L8VCC")
		(18 "In8.Cu" signal "L9GND")
		(20 "In9.Cu" signal "L10")
		(22 "In10.Cu" signal "L11GND")
		(24 "In11.Cu" signal "L12")
		(26 "In12.Cu" signal "L13GND")
		(2 "B.Cu" signal "BOTTOM")
		(9 "F.Adhes" user "F.Adhesive")
		(11 "B.Adhes" user "B.Adhesive")
		(13 "F.Paste" user "Package Geometry/Pastemask Top")
		(15 "B.Paste" user "Package Geometry/Pastemask Bottom")
		(5 "F.SilkS" user "Ref Des/Silkscreen Top")
		(7 "B.SilkS" user "Ref Des/Silkscreen Bottom")
		(1 "F.Mask" user "Board Geometry/Soldermask Top")
		(3 "B.Mask" user "Board Geometry/Soldermask Bottom")
		(17 "Dwgs.User" user "User.Drawings")
		(19 "Cmts.User" user "User.Comments")
		(21 "Eco1.User" user "User.Eco1")
		(23 "Eco2.User" user "User.Eco2")
		(25 "Edge.Cuts" user "Board Geometry/Outline")
		(27 "Margin" user)
		(31 "F.CrtYd" user "Package Geometry/Place Bound Top")
		(29 "B.CrtYd" user "Package Geometry/Place Bound Bottom")
		(35 "F.Fab" user "Ref Des/Assembly Top")
		(33 "B.Fab" user "Ref Des/Assembly Bottom")
	)
	(footprint ""
		(layer "F.Cu")
		(at 117.029992 -71.460614 -90)
		(property "Reference" "R3D19"
			(at 0 0 270)
			(layer "F.SilkS")
			(hide yes)
			(effects
				(font
					(size 1.27 1.27)
				)
			)
		)
		(property "Value" ""
			(at 0 0 270)
			(layer "F.Fab")
			(effects
				(font
					(size 1.27 1.27)
				)
			)
		)
		(duplicate_pad_numbers_are_jumpers no)
		(fp_poly
			(pts
				(xy -0.2794 -0.1016) (xy 0.2794 -0.1016) (xy 0.2794 0.9906) (xy -0.2794 0.9906)
			)
			(stroke
				(width 0)
				(type default)
			)
			(fill no)
			(layer "F.CrtYd")
		)
		(fp_line
			(start -0.2794 0.9906)
			(end 0.2794 0.9906)
			(stroke
				(width 0.1)
				(type default)
			)
			(layer "F.Fab")
		)
		(fp_line
			(start 0.2794 0.9906)
			(end 0.2794 -0.1016)
			(stroke
				(width 0.1)
				(type default)
			)
			(layer "F.Fab")
		)
		(fp_line
			(start -0.2794 -0.1016)
			(end -0.2794 0.9906)
			(stroke
				(width 0.1)
				(type default)
			)
			(layer "F.Fab")
		)
		(fp_line
			(start 0.2794 -0.1016)
			(end -0.2794 -0.1016)
			(stroke
				(width 0.1)
				(type default)
			)
			(layer "F.Fab")
		)
		(pad "1" smd rect
			(at 0 0 270)
			(size 0.508 0.508)
			(layers "F.Cu" "F.Mask" "F.Paste")
			(net "A_CPU1_UPI01_RBIAS")
		)
		(pad "2" smd rect
			(at 0 0.889 270)
			(size 0.508 0.508)
			(layers "F.Cu" "F.Mask" "F.Paste")
			(net "GND")
		)
		(zone
			(layer "F.Cu")
			(hatch none 0.5)
			(connect_pads
				(clearance 0)
			)
			(min_thickness 0.25)
			(keepout
				(tracks not_allowed)
				(vias allowed)
				(pads allowed)
				(copperpour not_allowed)
				(footprints allowed)
			)
			(placement
				(enabled no)
				(sheetname "")
			)
			(fill
				(thermal_gap 0.5)
				(thermal_bridge_width 0.5)
				(island_removal_mode 0)
			)
			(polygon
				(pts
					(xy 116.394992 -71.714614) (xy 116.394992 -71.206614) (xy 116.775992 -71.206614) (xy 116.775992 -71.714614)
				)
			)
		)
		(zone
			(layer "F.Cu")
			(hatch none 0.5)
			(connect_pads
				(clearance 0)
			)
			(min_thickness 0.25)
			(keepout
				(tracks allowed)
				(vias not_allowed)
				(pads allowed)
				(copperpour not_allowed)
				(footprints allowed)
			)
			(placement
				(enabled no)
				(sheetname "")
			)
			(fill
				(thermal_gap 0.5)
				(thermal_bridge_width 0.5)
				(island_removal_mode 0)
			)
			(polygon
				(pts
					(xy 116.775992 -71.714614) (xy 116.775992 -71.206614) (xy 116.394992 -71.206614) (xy 116.394992 -71.714614)
				)
			)
		)
	)
	(footprint ""
		(layer "F.Cu")
		(at 39.723568 -102.616 180)
		(property "Reference" "R1C6"
			(at 0 0 180)
			(layer "F.SilkS")
			(hide yes)
			(effects
				(font
					(size 1.27 1.27)
				)
			)
		)
		(property "Value" ""
			(at 0 0 180)
			(layer "F.Fab")
			(effects
				(font
					(size 1.27 1.27)
				)
			)
		)
		(duplicate_pad_numbers_are_jumpers no)
		(fp_poly
			(pts
				(xy -0.2794 -0.1016) (xy 0.2794 -0.1016) (xy 0.2794 0.9906) (xy -0.2794 0.9906)
			)
			(stroke
				(width 0)
				(type default)
			)
			(fill no)
			(layer "F.CrtYd")
		)
		(fp_line
			(start 0.2794 0.9906)
			(end 0.2794 -0.1016)
			(stroke
				(width 0.1)
				(type default)
			)
			(layer "F.Fab")
		)
		(fp_line
			(start 0.2794 -0.1016)
			(end -0.2794 -0.1016)
			(stroke
				(width 0.1)
				(type default)
			)
			(layer "F.Fab")
		)
		(fp_line
			(start -0.2794 0.9906)
			(end 0.2794 0.9906)
			(stroke
				(width 0.1)
				(type default)
			)
			(layer "F.Fab")
		)
		(fp_line
			(start -0.2794 -0.1016)
			(end -0.2794 0.9906)
			(stroke
				(width 0.1)
				(type default)
			)
			(layer "F.Fab")
		)
		(pad "1" smd rect
			(at 0 0 180)
			(size 0.508 0.508)
			(layers "F.Cu" "F.Mask" "F.Paste")
			(net "VSENSE_PVSA_CPU1_P")
		)
		(pad "2" smd rect
			(at 0 0.889 180)
			(size 0.508 0.508)
			(layers "F.Cu" "F.Mask" "F.Paste")
			(net "VSENSE_PVSA_CPU1_N")
		)
		(zone
			(layer "F.Cu")
			(hatch none 0.5)
			(connect_pads
				(clearance 0)
			)
			(min_thickness 0.25)
			(keepout
				(tracks not_allowed)
				(vias allowed)
				(pads allowed)
				(copperpour not_allowed)
				(footprints allowed)
			)
			(placement
				(enabled no)
				(sheetname "")
			)
			(fill
				(thermal_gap 0.5)
				(thermal_bridge_width 0.5)
				(island_removal_mode 0)
			)
			(polygon
				(pts
					(xy 39.977568 -103.251) (xy 39.469568 -103.251) (xy 39.469568 -102.87) (xy 39.977568 -102.87)
				)
			)
		)
		(zone
			(layer "F.Cu")
			(hatch none 0.5)
			(connect_pads
				(clearance 0)
			)
			(min_thickness 0.25)
			(keepout
				(tracks allowed)
				(vias not_allowed)
				(pads allowed)
				(copperpour not_allowed)
				(footprints allowed)
			)
			(placement
				(enabled no)
				(sheetname "")
			)
			(fill
				(thermal_gap 0.5)
				(thermal_bridge_width 0.5)
				(island_removal_mode 0)
			)
			(polygon
				(pts
					(xy 39.977568 -102.87) (xy 39.469568 -102.87) (xy 39.469568 -103.251) (xy 39.977568 -103.251)
				)
			)
		)
	)
)
